(kicad_pcb
	(version 20241229)
	(generator "pcbnew")
	(generator_version "9.0")
	(general
		(thickness 1.61)
		(legacy_teardrops no)
	)
	(paper "A3")
	(title_block
		(title "SO-DIMM DDR5 Tester")
		(date "2025-11-26")
		(rev "1.3.0")
		(comment 9 "footprints 492-497 of 627")
	)
	(layers
		(0 "F.Cu" signal)
		(4 "In1.Cu" power)
		(6 "In2.Cu" mixed)
		(8 "In3.Cu" power)
		(10 "In4.Cu" mixed)
		(12 "In5.Cu" power)
		(14 "In6.Cu" mixed)
		(16 "In7.Cu" power)
		(18 "In8.Cu" power)
		(20 "In9.Cu" mixed)
		(22 "In10.Cu" power)
		(2 "B.Cu" signal)
		(9 "F.Adhes" user "F.Adhesive")
		(11 "B.Adhes" user "B.Adhesive")
		(13 "F.Paste" user)
		(15 "B.Paste" user)
		(5 "F.SilkS" user "F.Silkscreen")
		(7 "B.SilkS" user "B.Silkscreen")
		(1 "F.Mask" user)
		(3 "B.Mask" user)
		(17 "Dwgs.User" user "User.Drawings")
		(19 "Cmts.User" user "User.Comments")
		(21 "Eco1.User" user "User.Eco1")
		(23 "Eco2.User" user "User.Eco2")
		(25 "Edge.Cuts" user)
		(27 "Margin" user)
		(31 "F.CrtYd" user "F.Courtyard")
		(29 "B.CrtYd" user "B.Courtyard")
		(35 "F.Fab" user)
		(33 "B.Fab" user)
	)
	(footprint "antmicro-footprints:C_0402_1005Metric"
		(layer "B.Cu")
		(at 128.375501 171.801 90)
		(descr "Capacitor SMD 0402 (1005 Metric), square (rectangular) end terminal, IPC_7351 nominal, (Body size source: IPC-SM-782 page 76, https://www.pcb-3d.com/wordpress/wp-content/uploads/ipc-sm-782a_amendment_1_and_2.pdf)")
		(tags "capacitor 0402")
		(property "Reference" "C58"
			(at 0 1.17 270)
			(layer "B.SilkS")
			(hide yes)
			(effects
				(font
					(size 0.7 0.7)
					(thickness 0.15)
				)
				(justify left bottom mirror)
			)
		)
		(property "Value" "C_100n_0402"
			(at 0 -1.169 270)
			(layer "B.Fab")
			(effects
				(font
					(size 0.7 0.7)
					(thickness 0.15)
				)
				(justify left bottom mirror)
			)
		)
		(property "Datasheet" "https://www.murata.com/products/productdetail?partno=GRM155R61H104KE14%23"
			(at 0 0 90)
			(layer "F.Fab")
			(hide yes)
			(effects
				(font
					(size 1.27 1.27)
					(thickness 0.15)
				)
			)
		)
		(property "Author" "Antmicro"
			(at 300.176501 43.425499 0)
			(layer "B.Fab")
			(hide yes)
			(effects
				(font
					(size 1 1)
					(thickness 0.15)
				)
				(justify mirror)
			)
		)
		(property "Dielectric" "X5R"
			(at 300.176501 43.425499 0)
			(layer "B.Fab")
			(hide yes)
			(effects
				(font
					(size 1 1)
					(thickness 0.15)
				)
				(justify mirror)
			)
		)
		(property "License" "Apache-2.0"
			(at 300.176501 43.425499 0)
			(layer "B.Fab")
			(hide yes)
			(effects
				(font
					(size 1 1)
					(thickness 0.15)
				)
				(justify mirror)
			)
		)
		(property "MPN" "GRM155R61H104KE14D"
			(at 300.176501 43.425499 0)
			(layer "B.Fab")
			(hide yes)
			(effects
				(font
					(size 1 1)
					(thickness 0.15)
				)
				(justify mirror)
			)
		)
		(property "Manufacturer" "Murata"
			(at 300.176501 43.425499 0)
			(layer "B.Fab")
			(hide yes)
			(effects
				(font
					(size 1 1)
					(thickness 0.15)
				)
				(justify mirror)
			)
		)
		(property "Val" "100n"
			(at 300.176501 43.425499 0)
			(layer "B.Fab")
			(hide yes)
			(effects
				(font
					(size 1 1)
					(thickness 0.15)
				)
				(justify mirror)
			)
		)
		(property "Voltage" "50V"
			(at 300.176501 43.425499 0)
			(layer "B.Fab")
			(hide yes)
			(effects
				(font
					(size 1 1)
					(thickness 0.15)
				)
				(justify mirror)
			)
		)
		(sheetname "/FPGA power/")
		(sheetfile "fpga-power.kicad_sch")
		(attr smd)
		(fp_rect
			(start -0.9656 0.4572)
			(end 0.9652 -0.4828)
			(stroke
				(width 0.05)
				(type solid)
			)
			(fill no)
			(layer "B.CrtYd")
		)
		(fp_line
			(start 0.498 -0.248)
			(end -0.5 -0.248)
			(stroke
				(width 0.15)
				(type solid)
			)
			(layer "B.Fab")
		)
		(fp_line
			(start -0.5 -0.248)
			(end -0.5 0.25)
			(stroke
				(width 0.15)
				(type solid)
			)
			(layer "B.Fab")
		)
		(fp_line
			(start 0.498 0.25)
			(end 0.498 -0.248)
			(stroke
				(width 0.15)
				(type solid)
			)
			(layer "B.Fab")
		)
		(fp_line
			(start -0.5 0.25)
			(end 0.498 0.25)
			(stroke
				(width 0.15)
				(type solid)
			)
			(layer "B.Fab")
		)
		(pad "1" smd roundrect
			(at -0.5 0)
			(size 0.6 0.6)
			(layers "B.Cu" "B.Mask" "B.Paste")
			(roundrect_rratio 0.25)
			(net 1 "GND")
			(pintype "passive")
		)
		(pad "2" smd roundrect
			(at 0.498 0 90)
			(size 0.6 0.6)
			(layers "B.Cu" "B.Mask" "B.Paste")
			(roundrect_rratio 0.25)
			(net 200 "+3V3")
			(pintype "passive")
		)
	)
	(footprint "antmicro-footprints:TP_SMD_1mm"
		(layer "B.Cu")
		(at 191.86 196.94 180)
		(property "Reference" "TP65"
			(at -1.24 -1.57 0)
			(layer "B.SilkS")
			(effects
				(font
					(size 0.7 0.7)
					(thickness 0.15)
				)
				(justify left bottom mirror)
			)
		)
		(property "Value" "TP_1mm_SMD"
			(at 0 -1.4 0)
			(layer "B.Fab")
			(effects
				(font
					(size 0.7 0.7)
					(thickness 0.15)
				)
				(justify left bottom mirror)
			)
		)
		(property "MPN" ""
			(at 0 0 0)
			(unlocked yes)
			(layer "B.Fab")
			(hide yes)
			(effects
				(font
					(size 1 1)
					(thickness 0.15)
				)
				(justify mirror)
			)
		)
		(property "Manufacturer" ""
			(at 0 0 0)
			(unlocked yes)
			(layer "B.Fab")
			(hide yes)
			(effects
				(font
					(size 1 1)
					(thickness 0.15)
				)
				(justify mirror)
			)
		)
		(property "Author" "Antmicro"
			(at 0 0 0)
			(unlocked yes)
			(layer "B.Fab")
			(hide yes)
			(effects
				(font
					(size 1 1)
					(thickness 0.15)
				)
				(justify mirror)
			)
		)
		(property "License" "Apache-2.0"
			(at 0 0 0)
			(unlocked yes)
			(layer "B.Fab")
			(hide yes)
			(effects
				(font
					(size 1 1)
					(thickness 0.15)
				)
				(justify mirror)
			)
		)
		(sheetname "/Supply/")
		(sheetfile "supply.kicad_sch")
		(attr exclude_from_pos_files)
		(fp_circle
			(center 0 0)
			(end 0.6 0)
			(stroke
				(width 0.05)
				(type default)
			)
			(fill no)
			(layer "B.CrtYd")
		)
		(fp_text user "${REFERENCE}"
			(at -0.5 -2.8 0)
			(layer "B.Fab")
			(effects
				(font
					(size 0.7 0.7)
					(thickness 0.15)
				)
				(justify left bottom mirror)
			)
		)
		(fp_text user "Author: Antmicro"
			(at -0.5 -4 0)
			(layer "B.Fab")
			(effects
				(font
					(size 0.7 0.7)
					(thickness 0.15)
				)
				(justify left bottom mirror)
			)
		)
		(fp_text user "License: Apache-2.0"
			(at -0.5 -5.2 0)
			(layer "B.Fab")
			(effects
				(font
					(size 0.7 0.7)
					(thickness 0.15)
				)
				(justify left bottom mirror)
			)
		)
		(pad "1" smd circle
			(at 0 0 180)
			(size 1 1)
			(layers "B.Cu" "B.Mask")
			(net 76 "/Supply/MGTAVTT_OUT")
			(pinfunction "1")
			(pintype "passive")
		)
	)
	(footprint "antmicro-footprints:C_0402_1005Metric"
		(layer "B.Cu")
		(at 131.375501 186.801 -90)
		(descr "Capacitor SMD 0402 (1005 Metric), square (rectangular) end terminal, IPC_7351 nominal, (Body size source: IPC-SM-782 page 76, https://www.pcb-3d.com/wordpress/wp-content/uploads/ipc-sm-782a_amendment_1_and_2.pdf)")
		(tags "capacitor 0402")
		(property "Reference" "C53"
			(at 0 1.17 90)
			(layer "B.SilkS")
			(hide yes)
			(effects
				(font
					(size 0.7 0.7)
					(thickness 0.15)
				)
				(justify left bottom mirror)
			)
		)
		(property "Value" "C_100n_0402"
			(at 0 -1.169 90)
			(layer "B.Fab")
			(effects
				(font
					(size 0.7 0.7)
					(thickness 0.15)
				)
				(justify left bottom mirror)
			)
		)
		(property "Datasheet" "https://www.murata.com/products/productdetail?partno=GRM155R61H104KE14%23"
			(at 0 0 270)
			(layer "F.Fab")
			(hide yes)
			(effects
				(font
					(size 1.27 1.27)
					(thickness 0.15)
				)
			)
		)
		(property "Author" "Antmicro"
			(at -55.425499 318.176501 0)
			(layer "B.Fab")
			(hide yes)
			(effects
				(font
					(size 1 1)
					(thickness 0.15)
				)
				(justify mirror)
			)
		)
		(property "Dielectric" "X5R"
			(at -55.425499 318.176501 0)
			(layer "B.Fab")
			(hide yes)
			(effects
				(font
					(size 1 1)
					(thickness 0.15)
				)
				(justify mirror)
			)
		)
		(property "License" "Apache-2.0"
			(at -55.425499 318.176501 0)
			(layer "B.Fab")
			(hide yes)
			(effects
				(font
					(size 1 1)
					(thickness 0.15)
				)
				(justify mirror)
			)
		)
		(property "MPN" "GRM155R61H104KE14D"
			(at -55.425499 318.176501 0)
			(layer "B.Fab")
			(hide yes)
			(effects
				(font
					(size 1 1)
					(thickness 0.15)
				)
				(justify mirror)
			)
		)
		(property "Manufacturer" "Murata"
			(at -55.425499 318.176501 0)
			(layer "B.Fab")
			(hide yes)
			(effects
				(font
					(size 1 1)
					(thickness 0.15)
				)
				(justify mirror)
			)
		)
		(property "Val" "100n"
			(at -55.425499 318.176501 0)
			(layer "B.Fab")
			(hide yes)
			(effects
				(font
					(size 1 1)
					(thickness 0.15)
				)
				(justify mirror)
			)
		)
		(property "Voltage" "50V"
			(at -55.425499 318.176501 0)
			(layer "B.Fab")
			(hide yes)
			(effects
				(font
					(size 1 1)
					(thickness 0.15)
				)
				(justify mirror)
			)
		)
		(sheetname "/FPGA power/")
		(sheetfile "fpga-power.kicad_sch")
		(attr smd)
		(fp_rect
			(start -0.9656 0.4572)
			(end 0.9652 -0.4828)
			(stroke
				(width 0.05)
				(type solid)
			)
			(fill no)
			(layer "B.CrtYd")
		)
		(fp_line
			(start -0.5 0.25)
			(end 0.498 0.25)
			(stroke
				(width 0.15)
				(type solid)
			)
			(layer "B.Fab")
		)
		(fp_line
			(start 0.498 0.25)
			(end 0.498 -0.248)
			(stroke
				(width 0.15)
				(type solid)
			)
			(layer "B.Fab")
		)
		(fp_line
			(start -0.5 -0.248)
			(end -0.5 0.25)
			(stroke
				(width 0.15)
				(type solid)
			)
			(layer "B.Fab")
		)
		(fp_line
			(start 0.498 -0.248)
			(end -0.5 -0.248)
			(stroke
				(width 0.15)
				(type solid)
			)
			(layer "B.Fab")
		)
		(pad "1" smd roundrect
			(at -0.5 0 180)
			(size 0.6 0.6)
			(layers "B.Cu" "B.Mask" "B.Paste")
			(roundrect_rratio 0.25)
			(net 1 "GND")
			(pintype "passive")
		)
		(pad "2" smd roundrect
			(at 0.498 0 270)
			(size 0.6 0.6)
			(layers "B.Cu" "B.Mask" "B.Paste")
			(roundrect_rratio 0.25)
			(net 200 "+3V3")
			(pintype "passive")
		)
	)
	(footprint "antmicro-footprints:TP_SMD_1mm"
		(layer "B.Cu")
		(at 201.5 161.6 180)
		(property "Reference" "TP62"
			(at -1.4 0.8 0)
			(layer "B.SilkS")
			(effects
				(font
					(size 0.7 0.7)
					(thickness 0.15)
				)
				(justify left bottom mirror)
			)
		)
		(property "Value" "TP_1mm_SMD"
			(at 0 -1.4 0)
			(layer "B.Fab")
			(effects
				(font
					(size 0.7 0.7)
					(thickness 0.15)
				)
				(justify left bottom mirror)
			)
		)
		(property "MPN" ""
			(at 0 0 0)
			(unlocked yes)
			(layer "B.Fab")
			(hide yes)
			(effects
				(font
					(size 1 1)
					(thickness 0.15)
				)
				(justify mirror)
			)
		)
		(property "Manufacturer" ""
			(at 0 0 0)
			(unlocked yes)
			(layer "B.Fab")
			(hide yes)
			(effects
				(font
					(size 1 1)
					(thickness 0.15)
				)
				(justify mirror)
			)
		)
		(property "Author" "Antmicro"
			(at 0 0 0)
			(unlocked yes)
			(layer "B.Fab")
			(hide yes)
			(effects
				(font
					(size 1 1)
					(thickness 0.15)
				)
				(justify mirror)
			)
		)
		(property "License" "Apache-2.0"
			(at 0 0 0)
			(unlocked yes)
			(layer "B.Fab")
			(hide yes)
			(effects
				(font
					(size 1 1)
					(thickness 0.15)
				)
				(justify mirror)
			)
		)
		(sheetname "/Supply/")
		(sheetfile "supply.kicad_sch")
		(attr exclude_from_pos_files)
		(fp_circle
			(center 0 0)
			(end 0.6 0)
			(stroke
				(width 0.05)
				(type default)
			)
			(fill no)
			(layer "B.CrtYd")
		)
		(fp_text user "Author: Antmicro"
			(at -0.5 -4 0)
			(layer "B.Fab")
			(effects
				(font
					(size 0.7 0.7)
					(thickness 0.15)
				)
				(justify left bottom mirror)
			)
		)
		(fp_text user "License: Apache-2.0"
			(at -0.5 -5.2 0)
			(layer "B.Fab")
			(effects
				(font
					(size 0.7 0.7)
					(thickness 0.15)
				)
				(justify left bottom mirror)
			)
		)
		(fp_text user "${REFERENCE}"
			(at -0.5 -2.8 0)
			(layer "B.Fab")
			(effects
				(font
					(size 0.7 0.7)
					(thickness 0.15)
				)
				(justify left bottom mirror)
			)
		)
		(pad "1" smd circle
			(at 0 0 180)
			(size 1 1)
			(layers "B.Cu" "B.Mask")
			(net 53 "/Supply/1V1_local")
			(pinfunction "1")
			(pintype "passive")
		)
	)
	(footprint "antmicro-footprints:C_0402_1005Metric"
		(layer "B.Cu")
		(at 136.877001 172.3025)
		(descr "Capacitor SMD 0402 (1005 Metric), square (rectangular) end terminal, IPC_7351 nominal, (Body size source: IPC-SM-782 page 76, https://www.pcb-3d.com/wordpress/wp-content/uploads/ipc-sm-782a_amendment_1_and_2.pdf)")
		(tags "capacitor 0402")
		(property "Reference" "C19"
			(at 0 1.17 180)
			(layer "B.SilkS")
			(hide yes)
			(effects
				(font
					(size 0.7 0.7)
					(thickness 0.15)
				)
				(justify left bottom mirror)
			)
		)
		(property "Value" "C_100n_0402"
			(at 0 -1.169 180)
			(layer "B.Fab")
			(effects
				(font
					(size 0.7 0.7)
					(thickness 0.15)
				)
				(justify left bottom mirror)
			)
		)
		(property "Datasheet" "https://www.murata.com/products/productdetail?partno=GRM155R61H104KE14%23"
			(at 0 0 0)
			(layer "F.Fab")
			(hide yes)
			(effects
				(font
					(size 1.27 1.27)
					(thickness 0.15)
				)
			)
		)
		(property "Author" "Antmicro"
			(at 0 0 0)
			(layer "B.Fab")
			(hide yes)
			(effects
				(font
					(size 1 1)
					(thickness 0.15)
				)
				(justify mirror)
			)
		)
		(property "Dielectric" "X5R"
			(at 0 0 0)
			(layer "B.Fab")
			(hide yes)
			(effects
				(font
					(size 1 1)
					(thickness 0.15)
				)
				(justify mirror)
			)
		)
		(property "License" "Apache-2.0"
			(at 0 0 0)
			(layer "B.Fab")
			(hide yes)
			(effects
				(font
					(size 1 1)
					(thickness 0.15)
				)
				(justify mirror)
			)
		)
		(property "MPN" "GRM155R61H104KE14D"
			(at 0 0 0)
			(layer "B.Fab")
			(hide yes)
			(effects
				(font
					(size 1 1)
					(thickness 0.15)
				)
				(justify mirror)
			)
		)
		(property "Manufacturer" "Murata"
			(at 0 0 0)
			(layer "B.Fab")
			(hide yes)
			(effects
				(font
					(size 1 1)
					(thickness 0.15)
				)
				(justify mirror)
			)
		)
		(property "Val" "100n"
			(at 0 0 0)
			(layer "B.Fab")
			(hide yes)
			(effects
				(font
					(size 1 1)
					(thickness 0.15)
				)
				(justify mirror)
			)
		)
		(property "Voltage" "50V"
			(at 0 0 0)
			(layer "B.Fab")
			(hide yes)
			(effects
				(font
					(size 1 1)
					(thickness 0.15)
				)
				(justify mirror)
			)
		)
		(sheetname "/FPGA power/")
		(sheetfile "fpga-power.kicad_sch")
		(attr smd)
		(fp_rect
			(start -0.9656 0.4572)
			(end 0.9652 -0.4828)
			(stroke
				(width 0.05)
				(type solid)
			)
			(fill no)
			(layer "B.CrtYd")
		)
		(fp_line
			(start -0.5 -0.248)
			(end -0.5 0.25)
			(stroke
				(width 0.15)
				(type solid)
			)
			(layer "B.Fab")
		)
		(fp_line
			(start -0.5 0.25)
			(end 0.498 0.25)
			(stroke
				(width 0.15)
				(type solid)
			)
			(layer "B.Fab")
		)
		(fp_line
			(start 0.498 -0.248)
			(end -0.5 -0.248)
			(stroke
				(width 0.15)
				(type solid)
			)
			(layer "B.Fab")
		)
		(fp_line
			(start 0.498 0.25)
			(end 0.498 -0.248)
			(stroke
				(width 0.15)
				(type solid)
			)
			(layer "B.Fab")
		)
		(pad "1" smd roundrect
			(at -0.5 0 270)
			(size 0.6 0.6)
			(layers "B.Cu" "B.Mask" "B.Paste")
			(roundrect_rratio 0.25)
			(net 1 "GND")
			(pintype "passive")
		)
		(pad "2" smd roundrect
			(at 0.498 0)
			(size 0.6 0.6)
			(layers "B.Cu" "B.Mask" "B.Paste")
			(roundrect_rratio 0.25)
			(net 227 "+1V0")
			(pintype "passive")
		)
	)
	(footprint "antmicro-footprints:C_0402_1005Metric"
		(layer "B.Cu")
		(at 131.375501 176.801 -90)
		(descr "Capacitor SMD 0402 (1005 Metric), square (rectangular) end terminal, IPC_7351 nominal, (Body size source: IPC-SM-782 page 76, https://www.pcb-3d.com/wordpress/wp-content/uploads/ipc-sm-782a_amendment_1_and_2.pdf)")
		(tags "capacitor 0402")
		(property "Reference" "C23"
			(at 0 1.17 90)
			(layer "B.SilkS")
			(hide yes)
			(effects
				(font
					(size 0.7 0.7)
					(thickness 0.15)
				)
				(justify left bottom mirror)
			)
		)
		(property "Value" "C_100n_0402"
			(at 0 -1.169 90)
			(layer "B.Fab")
			(effects
				(font
					(size 0.7 0.7)
					(thickness 0.15)
				)
				(justify left bottom mirror)
			)
		)
		(property "Datasheet" "https://www.murata.com/products/productdetail?partno=GRM155R61H104KE14%23"
			(at 0 0 270)
			(layer "F.Fab")
			(hide yes)
			(effects
				(font
					(size 1.27 1.27)
					(thickness 0.15)
				)
			)
		)
		(property "Author" "Antmicro"
			(at -45.425499 308.176501 0)
			(layer "B.Fab")
			(hide yes)
			(effects
				(font
					(size 1 1)
					(thickness 0.15)
				)
				(justify mirror)
			)
		)
		(property "Dielectric" "X5R"
			(at -45.425499 308.176501 0)
			(layer "B.Fab")
			(hide yes)
			(effects
				(font
					(size 1 1)
					(thickness 0.15)
				)
				(justify mirror)
			)
		)
		(property "License" "Apache-2.0"
			(at -45.425499 308.176501 0)
			(layer "B.Fab")
			(hide yes)
			(effects
				(font
					(size 1 1)
					(thickness 0.15)
				)
				(justify mirror)
			)
		)
		(property "MPN" "GRM155R61H104KE14D"
			(at -45.425499 308.176501 0)
			(layer "B.Fab")
			(hide yes)
			(effects
				(font
					(size 1 1)
					(thickness 0.15)
				)
				(justify mirror)
			)
		)
		(property "Manufacturer" "Murata"
			(at -45.425499 308.176501 0)
			(layer "B.Fab")
			(hide yes)
			(effects
				(font
					(size 1 1)
					(thickness 0.15)
				)
				(justify mirror)
			)
		)
		(property "Val" "100n"
			(at -45.425499 308.176501 0)
			(layer "B.Fab")
			(hide yes)
			(effects
				(font
					(size 1 1)
					(thickness 0.15)
				)
				(justify mirror)
			)
		)
		(property "Voltage" "50V"
			(at -45.425499 308.176501 0)
			(layer "B.Fab")
			(hide yes)
			(effects
				(font
					(size 1 1)
					(thickness 0.15)
				)
				(justify mirror)
			)
		)
		(sheetname "/FPGA power/")
		(sheetfile "fpga-power.kicad_sch")
		(attr smd)
		(fp_rect
			(start -0.9656 0.4572)
			(end 0.9652 -0.4828)
			(stroke
				(width 0.05)
				(type solid)
			)
			(fill no)
			(layer "B.CrtYd")
		)
		(fp_line
			(start -0.5 0.25)
			(end 0.498 0.25)
			(stroke
				(width 0.15)
				(type solid)
			)
			(layer "B.Fab")
		)
		(fp_line
			(start 0.498 0.25)
			(end 0.498 -0.248)
			(stroke
				(width 0.15)
				(type solid)
			)
			(layer "B.Fab")
		)
		(fp_line
			(start -0.5 -0.248)
			(end -0.5 0.25)
			(stroke
				(width 0.15)
				(type solid)
			)
			(layer "B.Fab")
		)
		(fp_line
			(start 0.498 -0.248)
			(end -0.5 -0.248)
			(stroke
				(width 0.15)
				(type solid)
			)
			(layer "B.Fab")
		)
		(pad "1" smd roundrect
			(at -0.5 0 180)
			(size 0.6 0.6)
			(layers "B.Cu" "B.Mask" "B.Paste")
			(roundrect_rratio 0.25)
			(net 1 "GND")
			(pintype "passive")
		)
		(pad "2" smd roundrect
			(at 0.498 0 270)
			(size 0.6 0.6)
			(layers "B.Cu" "B.Mask" "B.Paste")
			(roundrect_rratio 0.25)
			(net 200 "+3V3")
			(pintype "passive")
		)
	)
)
